(kicad_pcb
	(version 20241229)
	(generator "pcbnew")
	(generator_version "9.0")
	(general
		(thickness 1.62)
		(legacy_teardrops no)
	)
	(paper "A4")
	(title_block
		(title "OCuLink to 10GbE adapter")
		(date "2026-02-23")
		(rev "1.1.0")
		(company "Antmicro Ltd")
		(comment 1 "www.antmicro.com")
		(comment 9 "footprints 462-467 of 510")
	)
	(layers
		(0 "F.Cu" signal)
		(4 "In1.Cu" signal)
		(6 "In2.Cu" signal)
		(8 "In3.Cu" signal)
		(10 "In4.Cu" signal)
		(12 "In5.Cu" signal)
		(14 "In6.Cu" signal)
		(2 "B.Cu" signal)
		(9 "F.Adhes" user "F.Adhesive")
		(11 "B.Adhes" user "B.Adhesive")
		(13 "F.Paste" user)
		(15 "B.Paste" user)
		(5 "F.SilkS" user "F.Silkscreen")
		(7 "B.SilkS" user "B.Silkscreen")
		(1 "F.Mask" user)
		(3 "B.Mask" user)
		(17 "Dwgs.User" user "User.Drawings")
		(19 "Cmts.User" user "User.Comments")
		(21 "Eco1.User" user "User.Eco1")
		(23 "Eco2.User" user "User.Eco2")
		(25 "Edge.Cuts" user)
		(27 "Margin" user)
		(31 "F.CrtYd" user "F.Courtyard")
		(29 "B.CrtYd" user "B.Courtyard")
		(35 "F.Fab" user)
		(33 "B.Fab" user)
	)
	(footprint "antmicro-footprints:C_0402_1005Metric"
		(layer "B.Cu")
		(at 79.07 107.42 180)
		(descr "Capacitor SMD 0402")
		(tags "capacitor SMD 0402")
		(property "Reference" "C129"
			(at -1.52 -11.29 0)
			(layer "B.SilkS")
			(effects
				(font
					(size 0.7 0.7)
					(thickness 0.15)
				)
				(justify left bottom mirror)
			)
		)
		(property "Value" "C_1u_25V_0402"
			(at -1.022927 -2.155213 0)
			(layer "B.Fab")
			(hide yes)
			(effects
				(font
					(size 0.7 0.7)
					(thickness 0.15)
				)
				(justify left bottom mirror)
			)
		)
		(property "Datasheet" "https://www.murata.com/products/productdetail?partno=GRM155R61E105KE11%23"
			(at 0 0 0)
			(layer "B.Fab")
			(hide yes)
			(effects
				(font
					(size 1.27 1.27)
					(thickness 0.15)
				)
				(justify mirror)
			)
		)
		(property "Description" "SMD Multilayer Ceramic Capacitor, 1 µF, 25 V, 0402 [1005 Metric], ± 10%, X5R, GRM Series"
			(at 0 0 0)
			(layer "B.Fab")
			(hide yes)
			(effects
				(font
					(size 1.27 1.27)
					(thickness 0.15)
				)
				(justify mirror)
			)
		)
		(property "MPN" "GRM155R61E105KE11J"
			(at 0 0 180)
			(unlocked yes)
			(layer "B.Fab")
			(hide yes)
			(effects
				(font
					(size 1 1)
					(thickness 0.15)
				)
				(justify mirror)
			)
		)
		(property "Manufacturer" "Murata"
			(at 0 0 180)
			(unlocked yes)
			(layer "B.Fab")
			(hide yes)
			(effects
				(font
					(size 1 1)
					(thickness 0.15)
				)
				(justify mirror)
			)
		)
		(property "License" "Apache-2.0"
			(at 0 0 180)
			(unlocked yes)
			(layer "B.Fab")
			(hide yes)
			(effects
				(font
					(size 1 1)
					(thickness 0.15)
				)
				(justify mirror)
			)
		)
		(property "Author" "Antmicro"
			(at 0 0 180)
			(unlocked yes)
			(layer "B.Fab")
			(hide yes)
			(effects
				(font
					(size 1 1)
					(thickness 0.15)
				)
				(justify mirror)
			)
		)
		(property "Val" "1u"
			(at 0 0 180)
			(unlocked yes)
			(layer "B.Fab")
			(hide yes)
			(effects
				(font
					(size 1 1)
					(thickness 0.15)
				)
				(justify mirror)
			)
		)
		(property "Voltage" "25V"
			(at 0 0 180)
			(unlocked yes)
			(layer "B.Fab")
			(hide yes)
			(effects
				(font
					(size 1 1)
					(thickness 0.15)
				)
				(justify mirror)
			)
		)
		(property "Dielectric" "X5R"
			(at 0 0 180)
			(unlocked yes)
			(layer "B.Fab")
			(hide yes)
			(effects
				(font
					(size 1 1)
					(thickness 0.15)
				)
				(justify mirror)
			)
		)
		(sheetname "/X710-AT2 power/")
		(sheetfile "x710-at2-power.kicad_sch")
		(attr smd)
		(fp_rect
			(start -0.925 0.47)
			(end 0.925 -0.47)
			(stroke
				(width 0.05)
				(type default)
			)
			(fill no)
			(layer "B.CrtYd")
		)
		(fp_line
			(start 0.504 0.25)
			(end 0.504 -0.248)
			(stroke
				(width 0.15)
				(type solid)
			)
			(layer "B.Fab")
		)
		(fp_line
			(start 0.504 -0.248)
			(end -0.494 -0.248)
			(stroke
				(width 0.15)
				(type solid)
			)
			(layer "B.Fab")
		)
		(fp_line
			(start -0.494 0.25)
			(end 0.504 0.25)
			(stroke
				(width 0.15)
				(type solid)
			)
			(layer "B.Fab")
		)
		(fp_line
			(start -0.494 -0.248)
			(end -0.494 0.25)
			(stroke
				(width 0.15)
				(type solid)
			)
			(layer "B.Fab")
		)
		(pad "1" smd roundrect
			(at -0.48 0 180)
			(size 0.59 0.64)
			(layers "B.Cu" "B.Mask" "B.Paste")
			(roundrect_rratio 0.25)
			(net 28 "GND")
			(pintype "passive")
		)
		(pad "2" smd roundrect
			(at 0.48 0 180)
			(size 0.59 0.64)
			(layers "B.Cu" "B.Mask" "B.Paste")
			(roundrect_rratio 0.25)
			(net 23 "XGB_AVDDH")
			(pintype "passive")
		)
	)
	(footprint "antmicro-footprints:TP_SMD_0.75mm"
		(layer "B.Cu")
		(at 103.55 104.2 90)
		(property "Reference" "TP1"
			(at 0.44 0.41 180)
			(layer "B.SilkS")
			(effects
				(font
					(size 0.7 0.7)
					(thickness 0.15)
				)
				(justify right top mirror)
			)
		)
		(property "Value" "TP_0.75mm_SMD"
			(at 0 -1.2 90)
			(layer "B.Fab")
			(hide yes)
			(effects
				(font
					(size 0.7 0.7)
					(thickness 0.15)
				)
				(justify right top mirror)
			)
		)
		(property "Description" "SMT test point"
			(at 0 0 90)
			(layer "B.Fab")
			(hide yes)
			(effects
				(font
					(size 1.27 1.27)
					(thickness 0.15)
				)
				(justify mirror)
			)
		)
		(property "MPN" ""
			(at 0 0 90)
			(unlocked yes)
			(layer "B.Fab")
			(hide yes)
			(effects
				(font
					(size 1 1)
					(thickness 0.15)
				)
				(justify mirror)
			)
		)
		(property "Manufacturer" ""
			(at 0 0 90)
			(unlocked yes)
			(layer "B.Fab")
			(hide yes)
			(effects
				(font
					(size 1 1)
					(thickness 0.15)
				)
				(justify mirror)
			)
		)
		(property "Author" "Antmicro"
			(at 0 0 90)
			(unlocked yes)
			(layer "B.Fab")
			(hide yes)
			(effects
				(font
					(size 1 1)
					(thickness 0.15)
				)
				(justify mirror)
			)
		)
		(property "License" "Apache-2.0"
			(at 0 0 90)
			(unlocked yes)
			(layer "B.Fab")
			(hide yes)
			(effects
				(font
					(size 1 1)
					(thickness 0.15)
				)
				(justify mirror)
			)
		)
		(sheetname "/X710-AT2 Misc/")
		(sheetfile "x710-at2-mics.kicad_sch")
		(attr exclude_from_pos_files exclude_from_bom)
		(fp_circle
			(center 0 0)
			(end 0.475 0)
			(stroke
				(width 0.05)
				(type default)
			)
			(fill no)
			(layer "B.CrtYd")
		)
		(pad "1" smd circle
			(at 0 0 90)
			(size 0.75 0.75)
			(layers "B.Cu" "B.Mask")
			(net 368 "/X710-AT2 Misc/NCSI.ARB_IN")
			(pinfunction "1")
			(pintype "passive")
		)
	)
	(footprint "antmicro-footprints:R_0402_1005Metric"
		(layer "B.Cu")
		(at 74 95.65 180)
		(descr "Resistor SMD 0402")
		(tags "resistor SMD 0402")
		(property "Reference" "R91"
			(at 0.85 -0.45 0)
			(layer "B.SilkS")
			(effects
				(font
					(size 0.7 0.7)
					(thickness 0.15)
				)
				(justify left bottom mirror)
			)
		)
		(property "Value" "R_10k_0402"
			(at -1.011843 -1.772047 0)
			(layer "B.Fab")
			(hide yes)
			(effects
				(font
					(size 0.7 0.7)
					(thickness 0.15)
				)
				(justify left bottom mirror)
			)
		)
		(property "Datasheet" "https://www.bourns.com/docs/product-datasheets/cr.pdf"
			(at 0 0 0)
			(layer "B.Fab")
			(hide yes)
			(effects
				(font
					(size 1.27 1.27)
					(thickness 0.15)
				)
				(justify mirror)
			)
		)
		(property "Description" "SMD Chip Resistor, 10 kohm, ± 1%, 62.5 mW, 0402 [1005 Metric], Thick Film, General Purpose"
			(at 0 0 0)
			(layer "B.Fab")
			(hide yes)
			(effects
				(font
					(size 1.27 1.27)
					(thickness 0.15)
				)
				(justify mirror)
			)
		)
		(property "MPN" "CR0402-FX-1002GLF"
			(at 0 0 180)
			(unlocked yes)
			(layer "B.Fab")
			(hide yes)
			(effects
				(font
					(size 1 1)
					(thickness 0.15)
				)
				(justify mirror)
			)
		)
		(property "Manufacturer" "Bourns"
			(at 0 0 180)
			(unlocked yes)
			(layer "B.Fab")
			(hide yes)
			(effects
				(font
					(size 1 1)
					(thickness 0.15)
				)
				(justify mirror)
			)
		)
		(property "License" "Apache-2.0"
			(at 0 0 180)
			(unlocked yes)
			(layer "B.Fab")
			(hide yes)
			(effects
				(font
					(size 1 1)
					(thickness 0.15)
				)
				(justify mirror)
			)
		)
		(property "Author" "Antmicro"
			(at 0 0 180)
			(unlocked yes)
			(layer "B.Fab")
			(hide yes)
			(effects
				(font
					(size 1 1)
					(thickness 0.15)
				)
				(justify mirror)
			)
		)
		(property "Val" "10k"
			(at 0 0 180)
			(unlocked yes)
			(layer "B.Fab")
			(hide yes)
			(effects
				(font
					(size 1 1)
					(thickness 0.15)
				)
				(justify mirror)
			)
		)
		(property "Tolerance" "1%"
			(at 0 0 180)
			(unlocked yes)
			(layer "B.Fab")
			(hide yes)
			(effects
				(font
					(size 1 1)
					(thickness 0.15)
				)
				(justify mirror)
			)
		)
		(sheetname "/X710-AT2 Misc/")
		(sheetfile "x710-at2-mics.kicad_sch")
		(attr smd)
		(fp_rect
			(start -0.925 0.47)
			(end 0.925 -0.47)
			(stroke
				(width 0.05)
				(type default)
			)
			(fill no)
			(layer "B.CrtYd")
		)
		(fp_rect
			(start -0.5 0.25)
			(end 0.5 -0.25)
			(stroke
				(width 0.15)
				(type solid)
			)
			(fill no)
			(layer "B.Fab")
		)
		(pad "1" smd roundrect
			(at -0.48 0 180)
			(size 0.59 0.64)
			(layers "B.Cu" "B.Mask" "B.Paste")
			(roundrect_rratio 0.25)
			(net 97 "/X710-AT2 Misc/~{SMBALRT}")
			(pintype "passive")
		)
		(pad "2" smd roundrect
			(at 0.48 0 180)
			(size 0.59 0.64)
			(layers "B.Cu" "B.Mask" "B.Paste")
			(roundrect_rratio 0.25)
			(net 7 "+3V3")
			(pintype "passive")
		)
	)
	(footprint "antmicro-footprints:C_0402_1005Metric"
		(layer "B.Cu")
		(at 82.28 105.08 90)
		(descr "Capacitor SMD 0402")
		(tags "capacitor SMD 0402")
		(property "Reference" "C86"
			(at -11.81 0.21 90)
			(layer "B.SilkS")
			(effects
				(font
					(size 0.7 0.7)
					(thickness 0.15)
				)
				(justify right top mirror)
			)
		)
		(property "Value" "C_1u_25V_0402"
			(at -1.022927 -2.155213 90)
			(layer "B.Fab")
			(hide yes)
			(effects
				(font
					(size 0.7 0.7)
					(thickness 0.15)
				)
				(justify right top mirror)
			)
		)
		(property "Datasheet" "https://www.murata.com/products/productdetail?partno=GRM155R61E105KE11%23"
			(at 0 0 90)
			(layer "B.Fab")
			(hide yes)
			(effects
				(font
					(size 1.27 1.27)
					(thickness 0.15)
				)
				(justify mirror)
			)
		)
		(property "Description" "SMD Multilayer Ceramic Capacitor, 1 µF, 25 V, 0402 [1005 Metric], ± 10%, X5R, GRM Series"
			(at 0 0 90)
			(layer "B.Fab")
			(hide yes)
			(effects
				(font
					(size 1.27 1.27)
					(thickness 0.15)
				)
				(justify mirror)
			)
		)
		(property "MPN" "GRM155R61E105KE11J"
			(at 0 0 90)
			(unlocked yes)
			(layer "B.Fab")
			(hide yes)
			(effects
				(font
					(size 1 1)
					(thickness 0.15)
				)
				(justify mirror)
			)
		)
		(property "Manufacturer" "Murata"
			(at 0 0 90)
			(unlocked yes)
			(layer "B.Fab")
			(hide yes)
			(effects
				(font
					(size 1 1)
					(thickness 0.15)
				)
				(justify mirror)
			)
		)
		(property "License" "Apache-2.0"
			(at 0 0 90)
			(unlocked yes)
			(layer "B.Fab")
			(hide yes)
			(effects
				(font
					(size 1 1)
					(thickness 0.15)
				)
				(justify mirror)
			)
		)
		(property "Author" "Antmicro"
			(at 0 0 90)
			(unlocked yes)
			(layer "B.Fab")
			(hide yes)
			(effects
				(font
					(size 1 1)
					(thickness 0.15)
				)
				(justify mirror)
			)
		)
		(property "Val" "1u"
			(at 0 0 90)
			(unlocked yes)
			(layer "B.Fab")
			(hide yes)
			(effects
				(font
					(size 1 1)
					(thickness 0.15)
				)
				(justify mirror)
			)
		)
		(property "Voltage" "25V"
			(at 0 0 90)
			(unlocked yes)
			(layer "B.Fab")
			(hide yes)
			(effects
				(font
					(size 1 1)
					(thickness 0.15)
				)
				(justify mirror)
			)
		)
		(property "Dielectric" "X5R"
			(at 0 0 90)
			(unlocked yes)
			(layer "B.Fab")
			(hide yes)
			(effects
				(font
					(size 1 1)
					(thickness 0.15)
				)
				(justify mirror)
			)
		)
		(sheetname "/X710-AT2 power/")
		(sheetfile "x710-at2-power.kicad_sch")
		(attr smd)
		(fp_rect
			(start -0.925 0.47)
			(end 0.925 -0.47)
			(stroke
				(width 0.05)
				(type default)
			)
			(fill no)
			(layer "B.CrtYd")
		)
		(fp_line
			(start 0.504 -0.248)
			(end -0.494 -0.248)
			(stroke
				(width 0.15)
				(type solid)
			)
			(layer "B.Fab")
		)
		(fp_line
			(start -0.494 -0.248)
			(end -0.494 0.25)
			(stroke
				(width 0.15)
				(type solid)
			)
			(layer "B.Fab")
		)
		(fp_line
			(start 0.504 0.25)
			(end 0.504 -0.248)
			(stroke
				(width 0.15)
				(type solid)
			)
			(layer "B.Fab")
		)
		(fp_line
			(start -0.494 0.25)
			(end 0.504 0.25)
			(stroke
				(width 0.15)
				(type solid)
			)
			(layer "B.Fab")
		)
		(pad "1" smd roundrect
			(at -0.48 0 90)
			(size 0.59 0.64)
			(layers "B.Cu" "B.Mask" "B.Paste")
			(roundrect_rratio 0.25)
			(net 28 "GND")
			(pintype "passive")
		)
		(pad "2" smd roundrect
			(at 0.48 0 90)
			(size 0.59 0.64)
			(layers "B.Cu" "B.Mask" "B.Paste")
			(roundrect_rratio 0.25)
			(net 6 "DVDD")
			(pintype "passive")
		)
	)
	(footprint "antmicro-footprints:C_0402_1005Metric"
		(layer "B.Cu")
		(at 76.73 107.9 -90)
		(descr "Capacitor SMD 0402")
		(tags "capacitor SMD 0402")
		(property "Reference" "C167"
			(at 0.84 -0.33 90)
			(layer "B.SilkS")
			(effects
				(font
					(size 0.7 0.7)
					(thickness 0.15)
				)
				(justify left bottom mirror)
			)
		)
		(property "Value" "C_1u_25V_0402"
			(at -1.022927 -2.155213 90)
			(layer "B.Fab")
			(hide yes)
			(effects
				(font
					(size 0.7 0.7)
					(thickness 0.15)
				)
				(justify left bottom mirror)
			)
		)
		(property "Datasheet" "https://www.murata.com/products/productdetail?partno=GRM155R61E105KE11%23"
			(at 0 0 90)
			(layer "B.Fab")
			(hide yes)
			(effects
				(font
					(size 1.27 1.27)
					(thickness 0.15)
				)
				(justify mirror)
			)
		)
		(property "Description" "SMD Multilayer Ceramic Capacitor, 1 µF, 25 V, 0402 [1005 Metric], ± 10%, X5R, GRM Series"
			(at 0 0 90)
			(layer "B.Fab")
			(hide yes)
			(effects
				(font
					(size 1.27 1.27)
					(thickness 0.15)
				)
				(justify mirror)
			)
		)
		(property "MPN" "GRM155R61E105KE11J"
			(at 0 0 270)
			(unlocked yes)
			(layer "B.Fab")
			(hide yes)
			(effects
				(font
					(size 1 1)
					(thickness 0.15)
				)
				(justify mirror)
			)
		)
		(property "Manufacturer" "Murata"
			(at 0 0 270)
			(unlocked yes)
			(layer "B.Fab")
			(hide yes)
			(effects
				(font
					(size 1 1)
					(thickness 0.15)
				)
				(justify mirror)
			)
		)
		(property "License" "Apache-2.0"
			(at 0 0 270)
			(unlocked yes)
			(layer "B.Fab")
			(hide yes)
			(effects
				(font
					(size 1 1)
					(thickness 0.15)
				)
				(justify mirror)
			)
		)
		(property "Author" "Antmicro"
			(at 0 0 270)
			(unlocked yes)
			(layer "B.Fab")
			(hide yes)
			(effects
				(font
					(size 1 1)
					(thickness 0.15)
				)
				(justify mirror)
			)
		)
		(property "Val" "1u"
			(at 0 0 270)
			(unlocked yes)
			(layer "B.Fab")
			(hide yes)
			(effects
				(font
					(size 1 1)
					(thickness 0.15)
				)
				(justify mirror)
			)
		)
		(property "Voltage" "25V"
			(at 0 0 270)
			(unlocked yes)
			(layer "B.Fab")
			(hide yes)
			(effects
				(font
					(size 1 1)
					(thickness 0.15)
				)
				(justify mirror)
			)
		)
		(property "Dielectric" "X5R"
			(at 0 0 270)
			(unlocked yes)
			(layer "B.Fab")
			(hide yes)
			(effects
				(font
					(size 1 1)
					(thickness 0.15)
				)
				(justify mirror)
			)
		)
		(sheetname "/X710-AT2 power/")
		(sheetfile "x710-at2-power.kicad_sch")
		(attr smd)
		(fp_rect
			(start -0.925 0.47)
			(end 0.925 -0.47)
			(stroke
				(width 0.05)
				(type default)
			)
			(fill no)
			(layer "B.CrtYd")
		)
		(fp_line
			(start -0.494 0.25)
			(end 0.504 0.25)
			(stroke
				(width 0.15)
				(type solid)
			)
			(layer "B.Fab")
		)
		(fp_line
			(start 0.504 0.25)
			(end 0.504 -0.248)
			(stroke
				(width 0.15)
				(type solid)
			)
			(layer "B.Fab")
		)
		(fp_line
			(start -0.494 -0.248)
			(end -0.494 0.25)
			(stroke
				(width 0.15)
				(type solid)
			)
			(layer "B.Fab")
		)
		(fp_line
			(start 0.504 -0.248)
			(end -0.494 -0.248)
			(stroke
				(width 0.15)
				(type solid)
			)
			(layer "B.Fab")
		)
		(pad "1" smd roundrect
			(at -0.48 0 270)
			(size 0.59 0.64)
			(layers "B.Cu" "B.Mask" "B.Paste")
			(roundrect_rratio 0.25)
			(net 28 "GND")
			(pintype "passive")
		)
		(pad "2" smd roundrect
			(at 0.48 0 270)
			(size 0.59 0.64)
			(layers "B.Cu" "B.Mask" "B.Paste")
			(roundrect_rratio 0.25)
			(net 5 "P0_AVDDL")
			(pintype "passive")
		)
	)
	(footprint "antmicro-footprints:C_0402_1005Metric"
		(layer "B.Cu")
		(at 82.43 106.93 90)
		(descr "Capacitor SMD 0402")
		(tags "capacitor SMD 0402")
		(property "Reference" "C144"
			(at -12.72 0.11 90)
			(layer "B.SilkS")
			(effects
				(font
					(size 0.7 0.7)
					(thickness 0.15)
				)
				(justify right top mirror)
			)
		)
		(property "Value" "C_1u_25V_0402"
			(at -1.022927 -2.155213 90)
			(layer "B.Fab")
			(hide yes)
			(effects
				(font
					(size 0.7 0.7)
					(thickness 0.15)
				)
				(justify right top mirror)
			)
		)
		(property "Datasheet" "https://www.murata.com/products/productdetail?partno=GRM155R61E105KE11%23"
			(at 0 0 90)
			(layer "B.Fab")
			(hide yes)
			(effects
				(font
					(size 1.27 1.27)
					(thickness 0.15)
				)
				(justify mirror)
			)
		)
		(property "Description" "SMD Multilayer Ceramic Capacitor, 1 µF, 25 V, 0402 [1005 Metric], ± 10%, X5R, GRM Series"
			(at 0 0 90)
			(layer "B.Fab")
			(hide yes)
			(effects
				(font
					(size 1.27 1.27)
					(thickness 0.15)
				)
				(justify mirror)
			)
		)
		(property "MPN" "GRM155R61E105KE11J"
			(at 0 0 90)
			(unlocked yes)
			(layer "B.Fab")
			(hide yes)
			(effects
				(font
					(size 1 1)
					(thickness 0.15)
				)
				(justify mirror)
			)
		)
		(property "Manufacturer" "Murata"
			(at 0 0 90)
			(unlocked yes)
			(layer "B.Fab")
			(hide yes)
			(effects
				(font
					(size 1 1)
					(thickness 0.15)
				)
				(justify mirror)
			)
		)
		(property "License" "Apache-2.0"
			(at 0 0 90)
			(unlocked yes)
			(layer "B.Fab")
			(hide yes)
			(effects
				(font
					(size 1 1)
					(thickness 0.15)
				)
				(justify mirror)
			)
		)
		(property "Author" "Antmicro"
			(at 0 0 90)
			(unlocked yes)
			(layer "B.Fab")
			(hide yes)
			(effects
				(font
					(size 1 1)
					(thickness 0.15)
				)
				(justify mirror)
			)
		)
		(property "Val" "1u"
			(at 0 0 90)
			(unlocked yes)
			(layer "B.Fab")
			(hide yes)
			(effects
				(font
					(size 1 1)
					(thickness 0.15)
				)
				(justify mirror)
			)
		)
		(property "Voltage" "25V"
			(at 0 0 90)
			(unlocked yes)
			(layer "B.Fab")
			(hide yes)
			(effects
				(font
					(size 1 1)
					(thickness 0.15)
				)
				(justify mirror)
			)
		)
		(property "Dielectric" "X5R"
			(at 0 0 90)
			(unlocked yes)
			(layer "B.Fab")
			(hide yes)
			(effects
				(font
					(size 1 1)
					(thickness 0.15)
				)
				(justify mirror)
			)
		)
		(sheetname "/X710-AT2 power/")
		(sheetfile "x710-at2-power.kicad_sch")
		(attr smd)
		(fp_rect
			(start -0.925 0.47)
			(end 0.925 -0.47)
			(stroke
				(width 0.05)
				(type default)
			)
			(fill no)
			(layer "B.CrtYd")
		)
		(fp_line
			(start 0.504 -0.248)
			(end -0.494 -0.248)
			(stroke
				(width 0.15)
				(type solid)
			)
			(layer "B.Fab")
		)
		(fp_line
			(start -0.494 -0.248)
			(end -0.494 0.25)
			(stroke
				(width 0.15)
				(type solid)
			)
			(layer "B.Fab")
		)
		(fp_line
			(start 0.504 0.25)
			(end 0.504 -0.248)
			(stroke
				(width 0.15)
				(type solid)
			)
			(layer "B.Fab")
		)
		(fp_line
			(start -0.494 0.25)
			(end 0.504 0.25)
			(stroke
				(width 0.15)
				(type solid)
			)
			(layer "B.Fab")
		)
		(pad "1" smd roundrect
			(at -0.48 0 90)
			(size 0.59 0.64)
			(layers "B.Cu" "B.Mask" "B.Paste")
			(roundrect_rratio 0.25)
			(net 28 "GND")
			(pintype "passive")
		)
		(pad "2" smd roundrect
			(at 0.48 0 90)
			(size 0.59 0.64)
			(layers "B.Cu" "B.Mask" "B.Paste")
			(roundrect_rratio 0.25)
			(net 10 "AVDDH")
			(pintype "passive")
		)
	)
)
